FILE_TYPE=LIBRARY_PARTS;
primitive 'SCONN16_ACASPI006P06';
  pin
    'VCC':
      PIN_NUMBER='(2)';
      PINUSE='POWER';
      NO_LOAD_CHECK='Both';
      NO_IO_CHECK='Both';
      NO_DIR_CHECK='TRUE';
      NO_ASSERT_CHECK='TRUE';
      ALLOW_CONNECT='TRUE';
    'HOLD_N':
      PIN_NUMBER='(1)';
      BIDIRECTIONAL='TRUE';
      INPUT_LOAD='(-0.01,0.01)';
      OUTPUT_LOAD='(1.0,-1.0)';
    'CS_N':
      PIN_NUMBER='(7)';
      BIDIRECTIONAL='TRUE';
      INPUT_LOAD='(-0.01,0.01)';
      OUTPUT_LOAD='(1.0,-1.0)';
    'WP_N':
      PIN_NUMBER='(9)';
      BIDIRECTIONAL='TRUE';
      INPUT_LOAD='(-0.01,0.01)';
      OUTPUT_LOAD='(1.0,-1.0)';
    'DI':
      PIN_NUMBER='(15)';
      BIDIRECTIONAL='TRUE';
      INPUT_LOAD='(-0.01,0.01)';
      OUTPUT_LOAD='(1.0,-1.0)';
    'CLK':
      PIN_NUMBER='(16)';
      BIDIRECTIONAL='TRUE';
      INPUT_LOAD='(-0.01,0.01)';
      OUTPUT_LOAD='(1.0,-1.0)';
    'GND':
      PIN_NUMBER='(10)';
      PINUSE='POWER';
      NO_LOAD_CHECK='Both';
      NO_IO_CHECK='Both';
      NO_DIR_CHECK='TRUE';
      NO_ASSERT_CHECK='TRUE';
      ALLOW_CONNECT='TRUE';
    'DO':
      PIN_NUMBER='(8)';
      BIDIRECTIONAL='TRUE';
      INPUT_LOAD='(-0.01,0.01)';
      OUTPUT_LOAD='(1.0,-1.0)';
    'NC0':
      PIN_NUMBER='(3)';
      BIDIRECTIONAL='TRUE';
      INPUT_LOAD='(-0.01,0.01)';
      OUTPUT_LOAD='(1.0,-1.0)';
    'NC1':
      PIN_NUMBER='(4)';
      BIDIRECTIONAL='TRUE';
      INPUT_LOAD='(-0.01,0.01)';
      OUTPUT_LOAD='(1.0,-1.0)';
    'NC2':
      PIN_NUMBER='(5)';
      BIDIRECTIONAL='TRUE';
      INPUT_LOAD='(-0.01,0.01)';
      OUTPUT_LOAD='(1.0,-1.0)';
    'NC3':
      PIN_NUMBER='(6)';
      BIDIRECTIONAL='TRUE';
      INPUT_LOAD='(-0.01,0.01)';
      OUTPUT_LOAD='(1.0,-1.0)';
    'NC4':
      PIN_NUMBER='(11)';
      BIDIRECTIONAL='TRUE';
      INPUT_LOAD='(-0.01,0.01)';
      OUTPUT_LOAD='(1.0,-1.0)';
    'NC6':
      PIN_NUMBER='(12)';
      BIDIRECTIONAL='TRUE';
      INPUT_LOAD='(-0.01,0.01)';
      OUTPUT_LOAD='(1.0,-1.0)';
    'NC7':
      PIN_NUMBER='(13)';
      BIDIRECTIONAL='TRUE';
      INPUT_LOAD='(-0.01,0.01)';
      OUTPUT_LOAD='(1.0,-1.0)';
    'NC8':
      PIN_NUMBER='(14)';
      BIDIRECTIONAL='TRUE';
      INPUT_LOAD='(-0.01,0.01)';
      OUTPUT_LOAD='(1.0,-1.0)';
  end_pin;
  body
    PART_NAME='SCONN16_ACASPI006P06';
    BODY_NAME='SCONN16_ACASPI006P06';
    PHYS_DES_PREFIX='U';
    CLASS='IC';
  end_body;
end_primitive;

END.
